(kicad_pcb
	(version 20260206)
	(generator "pcbnew")
	(generator_version "10.0")
	(general
		(thickness 1.6)
		(legacy_teardrops no)
	)
	(paper "A4")
	(title_block
		(title "fcb — 12433-1M.1206WZS1330.brd")
		(comment 1 "Open Vault / Knox (Wiwynn) / footprints 184-187 of 495")
	)
	(layers
		(0 "F.Cu" signal "TOP")
		(4 "In1.Cu" signal "L2GND")
		(6 "In2.Cu" signal "L3VCC")
		(2 "B.Cu" signal "BOTTOM")
		(9 "F.Adhes" user "F.Adhesive")
		(11 "B.Adhes" user "B.Adhesive")
		(13 "F.Paste" user "Package Geometry/Pastemask Top")
		(15 "B.Paste" user "Package Geometry/Pastemask Bottom")
		(5 "F.SilkS" user "Ref Des/Silkscreen Top")
		(7 "B.SilkS" user "Ref Des/Silkscreen Bottom")
		(1 "F.Mask" user "Board Geometry/Soldermask Top")
		(3 "B.Mask" user "Board Geometry/Soldermask Bottom")
		(17 "Dwgs.User" user "User.Drawings")
		(19 "Cmts.User" user "User.Comments")
		(21 "Eco1.User" user "User.Eco1")
		(23 "Eco2.User" user "User.Eco2")
		(25 "Edge.Cuts" user "Board Geometry/Outline")
		(27 "Margin" user)
		(31 "F.CrtYd" user "Package Geometry/Place Bound Top")
		(29 "B.CrtYd" user "Package Geometry/Place Bound Bottom")
		(35 "F.Fab" user "Ref Des/Assembly Top")
		(33 "B.Fab" user "Ref Des/Assembly Bottom")
	)
	(footprint ""
		(layer "F.Cu")
		(at 4.499864 -340.000082)
		(property "Reference" "H4"
			(at 0 0 0)
			(layer "F.SilkS")
			(hide yes)
			(effects
				(font
					(size 1.27 1.27)
				)
			)
		)
		(property "Value" "HOLE315R138"
			(at 0 -7.0612 0)
			(unlocked yes)
			(layer "F.Fab")
			(hide yes)
			(effects
				(font
					(size 1.016 1.016)
					(thickness 0.1524)
				)
			)
		)
		(property "Device Type" "HOLE315R138"
			(at 0 -8.5852 0)
			(unlocked yes)
			(layer "F.Fab")
			(hide yes)
			(effects
				(font
					(size 1.016 1.016)
					(thickness 0.1524)
				)
			)
		)
		(duplicate_pad_numbers_are_jumpers no)
		(fp_poly
			(pts
				(xy 0 4.3053) (xy -0.13462 4.30276) (xy -0.27051 4.29641) (xy -0.40513 4.28625) (xy -0.53975 4.27101)
				(xy -0.6731 4.25196) (xy -0.80645 4.2291) (xy -0.9398 4.20116) (xy -1.07061 4.17068) (xy -1.20142 4.13385)
				(xy -1.33096 4.09448) (xy -1.45796 4.0513) (xy -1.58496 4.00304) (xy -1.70942 3.95097) (xy -1.83261 3.89509)
				(xy -1.95453 3.83667) (xy -2.07391 3.77317) (xy -2.19202 3.70586) (xy -2.30632 3.63474) (xy -2.41935 3.56108)
				(xy -2.53111 3.48361) (xy -2.63906 3.40233) (xy -2.74447 3.31724) (xy -2.84734 3.22961) (xy -2.94767 3.13817)
				(xy -3.04419 3.04419) (xy -3.13817 2.94767) (xy -3.22961 2.84734) (xy -3.31724 2.74447) (xy -3.40233 2.63906)
				(xy -3.48361 2.53111) (xy -3.56108 2.41935) (xy -3.63474 2.30632) (xy -3.70586 2.19202) (xy -3.77317 2.07391)
				(xy -3.83667 1.95453) (xy -3.89509 1.83261) (xy -3.95097 1.70942) (xy -4.00304 1.58496) (xy -4.0513 1.45796)
				(xy -4.09448 1.33096) (xy -4.13385 1.20142) (xy -4.17068 1.07061) (xy -4.20116 0.9398) (xy -4.2291 0.80645)
				(xy -4.25196 0.6731) (xy -4.27101 0.53975) (xy -4.28625 0.40513) (xy -4.29641 0.27051) (xy -4.30276 0.13462)
				(xy -4.3053 0) (xy -4.30276 -0.13462) (xy -4.29641 -0.27051) (xy -4.28625 -0.40513) (xy -4.27101 -0.53975)
				(xy -4.25196 -0.6731) (xy -4.2291 -0.80645) (xy -4.20116 -0.9398) (xy -4.17068 -1.07061) (xy -4.13385 -1.20142)
				(xy -4.09448 -1.33096) (xy -4.0513 -1.45796) (xy -4.00304 -1.58496) (xy -3.95097 -1.70942) (xy -3.89509 -1.83261)
				(xy -3.83667 -1.95453) (xy -3.77317 -2.07391) (xy -3.70586 -2.19202) (xy -3.63474 -2.30632) (xy -3.56108 -2.41935)
				(xy -3.48361 -2.53111) (xy -3.40233 -2.63906) (xy -3.31724 -2.74447) (xy -3.22961 -2.84734) (xy -3.13817 -2.94767)
				(xy -3.04419 -3.04419) (xy -2.94767 -3.13817) (xy -2.84734 -3.22961) (xy -2.74447 -3.31724) (xy -2.63906 -3.40233)
				(xy -2.53111 -3.48361) (xy -2.41935 -3.56108) (xy -2.30632 -3.63474) (xy -2.19202 -3.70586) (xy -2.07391 -3.77317)
				(xy -1.95453 -3.83667) (xy -1.83261 -3.89509) (xy -1.70942 -3.95097) (xy -1.58496 -4.00304) (xy -1.45796 -4.0513)
				(xy -1.33096 -4.09448) (xy -1.20142 -4.13385) (xy -1.07061 -4.17068) (xy -0.9398 -4.20116) (xy -0.80645 -4.2291)
				(xy -0.6731 -4.25196) (xy -0.53975 -4.27101) (xy -0.40513 -4.28625) (xy -0.27051 -4.29641) (xy -0.13462 -4.30276)
				(xy 0 -4.3053) (xy 0.13462 -4.30276) (xy 0.27051 -4.29641) (xy 0.40513 -4.28625) (xy 0.53975 -4.27101)
				(xy 0.6731 -4.25196) (xy 0.80645 -4.2291) (xy 0.9398 -4.20116) (xy 1.07061 -4.17068) (xy 1.20142 -4.13385)
				(xy 1.33096 -4.09448) (xy 1.45796 -4.0513) (xy 1.58496 -4.00304) (xy 1.70942 -3.95097) (xy 1.83261 -3.89509)
				(xy 1.95453 -3.83667) (xy 2.07391 -3.77317) (xy 2.19202 -3.70586) (xy 2.30632 -3.63474) (xy 2.41935 -3.56108)
				(xy 2.53111 -3.48361) (xy 2.63906 -3.40233) (xy 2.74447 -3.31724) (xy 2.84734 -3.22961) (xy 2.94767 -3.13817)
				(xy 3.04419 -3.04419) (xy 3.13817 -2.94767) (xy 3.22961 -2.84734) (xy 3.31724 -2.74447) (xy 3.40233 -2.63906)
				(xy 3.48361 -2.53111) (xy 3.56108 -2.41935) (xy 3.63474 -2.30632) (xy 3.70586 -2.19202) (xy 3.77317 -2.07391)
				(xy 3.83667 -1.95453) (xy 3.89509 -1.83261) (xy 3.95097 -1.70942) (xy 4.00304 -1.58496) (xy 4.0513 -1.45796)
				(xy 4.09448 -1.33096) (xy 4.13385 -1.20142) (xy 4.17068 -1.07061) (xy 4.20116 -0.9398) (xy 4.2291 -0.80645)
				(xy 4.25196 -0.6731) (xy 4.27101 -0.53975) (xy 4.28625 -0.40513) (xy 4.29641 -0.27051) (xy 4.30276 -0.13462)
				(xy 4.3053 0) (xy 4.30276 0.13462) (xy 4.29641 0.27051) (xy 4.28625 0.40513) (xy 4.27101 0.53975)
				(xy 4.25196 0.6731) (xy 4.2291 0.80645) (xy 4.20116 0.9398) (xy 4.17068 1.07061) (xy 4.13385 1.20142)
				(xy 4.09448 1.33096) (xy 4.0513 1.45796) (xy 4.00304 1.58496) (xy 3.95097 1.70942) (xy 3.89509 1.83261)
				(xy 3.83667 1.95453) (xy 3.77317 2.07391) (xy 3.70586 2.19202) (xy 3.63474 2.30632) (xy 3.56108 2.41935)
				(xy 3.48361 2.53111) (xy 3.40233 2.63906) (xy 3.31724 2.74447) (xy 3.22961 2.84734) (xy 3.13817 2.94767)
				(xy 3.04419 3.04419) (xy 2.94767 3.13817) (xy 2.84734 3.22961) (xy 2.74447 3.31724) (xy 2.63906 3.40233)
				(xy 2.53111 3.48361) (xy 2.41935 3.56108) (xy 2.30632 3.63474) (xy 2.19202 3.70586) (xy 2.07391 3.77317)
				(xy 1.95453 3.83667) (xy 1.83261 3.89509) (xy 1.70942 3.95097) (xy 1.58496 4.00304) (xy 1.45796 4.0513)
				(xy 1.33096 4.09448) (xy 1.20142 4.13385) (xy 1.07061 4.17068) (xy 0.9398 4.20116) (xy 0.80645 4.2291)
				(xy 0.6731 4.25196) (xy 0.53975 4.27101) (xy 0.40513 4.28625) (xy 0.27051 4.29641) (xy 0.13462 4.30276)
			)
			(stroke
				(width 0)
				(type default)
			)
			(fill no)
			(layer "F.CrtYd")
		)
		(fp_poly
			(pts
				(xy 0 4.3053) (xy -0.13462 4.30276) (xy -0.27051 4.29641) (xy -0.40513 4.28625) (xy -0.53975 4.27101)
				(xy -0.6731 4.25196) (xy -0.80645 4.2291) (xy -0.9398 4.20116) (xy -1.07061 4.17068) (xy -1.20142 4.13385)
				(xy -1.33096 4.09448) (xy -1.45796 4.0513) (xy -1.58496 4.00304) (xy -1.70942 3.95097) (xy -1.83261 3.89509)
				(xy -1.95453 3.83667) (xy -2.07391 3.77317) (xy -2.19202 3.70586) (xy -2.30632 3.63474) (xy -2.41935 3.56108)
				(xy -2.53111 3.48361) (xy -2.63906 3.40233) (xy -2.74447 3.31724) (xy -2.84734 3.22961) (xy -2.94767 3.13817)
				(xy -3.04419 3.04419) (xy -3.13817 2.94767) (xy -3.22961 2.84734) (xy -3.31724 2.74447) (xy -3.40233 2.63906)
				(xy -3.48361 2.53111) (xy -3.56108 2.41935) (xy -3.63474 2.30632) (xy -3.70586 2.19202) (xy -3.77317 2.07391)
				(xy -3.83667 1.95453) (xy -3.89509 1.83261) (xy -3.95097 1.70942) (xy -4.00304 1.58496) (xy -4.0513 1.45796)
				(xy -4.09448 1.33096) (xy -4.13385 1.20142) (xy -4.17068 1.07061) (xy -4.20116 0.9398) (xy -4.2291 0.80645)
				(xy -4.25196 0.6731) (xy -4.27101 0.53975) (xy -4.28625 0.40513) (xy -4.29641 0.27051) (xy -4.30276 0.13462)
				(xy -4.3053 0) (xy -4.30276 -0.13462) (xy -4.29641 -0.27051) (xy -4.28625 -0.40513) (xy -4.27101 -0.53975)
				(xy -4.25196 -0.6731) (xy -4.2291 -0.80645) (xy -4.20116 -0.9398) (xy -4.17068 -1.07061) (xy -4.13385 -1.20142)
				(xy -4.09448 -1.33096) (xy -4.0513 -1.45796) (xy -4.00304 -1.58496) (xy -3.95097 -1.70942) (xy -3.89509 -1.83261)
				(xy -3.83667 -1.95453) (xy -3.77317 -2.07391) (xy -3.70586 -2.19202) (xy -3.63474 -2.30632) (xy -3.56108 -2.41935)
				(xy -3.48361 -2.53111) (xy -3.40233 -2.63906) (xy -3.31724 -2.74447) (xy -3.22961 -2.84734) (xy -3.13817 -2.94767)
				(xy -3.04419 -3.04419) (xy -2.94767 -3.13817) (xy -2.84734 -3.22961) (xy -2.74447 -3.31724) (xy -2.63906 -3.40233)
				(xy -2.53111 -3.48361) (xy -2.41935 -3.56108) (xy -2.30632 -3.63474) (xy -2.19202 -3.70586) (xy -2.07391 -3.77317)
				(xy -1.95453 -3.83667) (xy -1.83261 -3.89509) (xy -1.70942 -3.95097) (xy -1.58496 -4.00304) (xy -1.45796 -4.0513)
				(xy -1.33096 -4.09448) (xy -1.20142 -4.13385) (xy -1.07061 -4.17068) (xy -0.9398 -4.20116) (xy -0.80645 -4.2291)
				(xy -0.6731 -4.25196) (xy -0.53975 -4.27101) (xy -0.40513 -4.28625) (xy -0.27051 -4.29641) (xy -0.13462 -4.30276)
				(xy 0 -4.3053) (xy 0.13462 -4.30276) (xy 0.27051 -4.29641) (xy 0.40513 -4.28625) (xy 0.53975 -4.27101)
				(xy 0.6731 -4.25196) (xy 0.80645 -4.2291) (xy 0.9398 -4.20116) (xy 1.07061 -4.17068) (xy 1.20142 -4.13385)
				(xy 1.33096 -4.09448) (xy 1.45796 -4.0513) (xy 1.58496 -4.00304) (xy 1.70942 -3.95097) (xy 1.83261 -3.89509)
				(xy 1.95453 -3.83667) (xy 2.07391 -3.77317) (xy 2.19202 -3.70586) (xy 2.30632 -3.63474) (xy 2.41935 -3.56108)
				(xy 2.53111 -3.48361) (xy 2.63906 -3.40233) (xy 2.74447 -3.31724) (xy 2.84734 -3.22961) (xy 2.94767 -3.13817)
				(xy 3.04419 -3.04419) (xy 3.13817 -2.94767) (xy 3.22961 -2.84734) (xy 3.31724 -2.74447) (xy 3.40233 -2.63906)
				(xy 3.48361 -2.53111) (xy 3.56108 -2.41935) (xy 3.63474 -2.30632) (xy 3.70586 -2.19202) (xy 3.77317 -2.07391)
				(xy 3.83667 -1.95453) (xy 3.89509 -1.83261) (xy 3.95097 -1.70942) (xy 4.00304 -1.58496) (xy 4.0513 -1.45796)
				(xy 4.09448 -1.33096) (xy 4.13385 -1.20142) (xy 4.17068 -1.07061) (xy 4.20116 -0.9398) (xy 4.2291 -0.80645)
				(xy 4.25196 -0.6731) (xy 4.27101 -0.53975) (xy 4.28625 -0.40513) (xy 4.29641 -0.27051) (xy 4.30276 -0.13462)
				(xy 4.3053 0) (xy 4.30276 0.13462) (xy 4.29641 0.27051) (xy 4.28625 0.40513) (xy 4.27101 0.53975)
				(xy 4.25196 0.6731) (xy 4.2291 0.80645) (xy 4.20116 0.9398) (xy 4.17068 1.07061) (xy 4.13385 1.20142)
				(xy 4.09448 1.33096) (xy 4.0513 1.45796) (xy 4.00304 1.58496) (xy 3.95097 1.70942) (xy 3.89509 1.83261)
				(xy 3.83667 1.95453) (xy 3.77317 2.07391) (xy 3.70586 2.19202) (xy 3.63474 2.30632) (xy 3.56108 2.41935)
				(xy 3.48361 2.53111) (xy 3.40233 2.63906) (xy 3.31724 2.74447) (xy 3.22961 2.84734) (xy 3.13817 2.94767)
				(xy 3.04419 3.04419) (xy 2.94767 3.13817) (xy 2.84734 3.22961) (xy 2.74447 3.31724) (xy 2.63906 3.40233)
				(xy 2.53111 3.48361) (xy 2.41935 3.56108) (xy 2.30632 3.63474) (xy 2.19202 3.70586) (xy 2.07391 3.77317)
				(xy 1.95453 3.83667) (xy 1.83261 3.89509) (xy 1.70942 3.95097) (xy 1.58496 4.00304) (xy 1.45796 4.0513)
				(xy 1.33096 4.09448) (xy 1.20142 4.13385) (xy 1.07061 4.17068) (xy 0.9398 4.20116) (xy 0.80645 4.2291)
				(xy 0.6731 4.25196) (xy 0.53975 4.27101) (xy 0.40513 4.28625) (xy 0.27051 4.29641) (xy 0.13462 4.30276)
			)
			(stroke
				(width 0)
				(type default)
			)
			(fill no)
			(layer "F.Fab")
		)
		(pad "1" thru_hole circle
			(at 0 0)
			(size 8.001 8.001)
			(drill 3.5052)
			(layers "*.Cu" "*.Mask")
			(remove_unused_layers no)
			(net "GND")
			(clearance -1.7399)
			(thermal_gap 0.3048)
			(padstack
				(mode front_inner_back)
				(layer "Inner"
					(shape circle)
					(size 3.9116 3.9116)
					(clearance 0.3048)
				)
				(layer "B.Cu"
					(shape circle)
					(size 8.001 8.001)
					(clearance -1.7399)
				)
			)
		)
	)
	(footprint ""
		(layer "F.Cu")
		(at 21.489162 -13.843508 90)
		(property "Reference" "D3"
			(at 0 0 90)
			(layer "F.SilkS")
			(hide yes)
			(effects
				(font
					(size 1.27 1.27)
				)
			)
		)
		(property "Value" "BAS16H-GP"
			(at 0 -5.5372 90)
			(unlocked yes)
			(layer "F.Fab")
			(hide yes)
			(effects
				(font
					(size 1.016 1.016)
					(thickness 0.1524)
				)
			)
		)
		(property "Device Type" "SOD123AKH48"
			(at 0 -7.0612 90)
			(unlocked yes)
			(layer "F.Fab")
			(hide yes)
			(effects
				(font
					(size 1.016 1.016)
					(thickness 0.1524)
				)
			)
		)
		(duplicate_pad_numbers_are_jumpers no)
		(fp_line
			(start 1.016 -2.667)
			(end -1.016 -2.667)
			(stroke
				(width 0.1524)
				(type default)
			)
			(layer "F.SilkS")
		)
		(fp_line
			(start -1.016 -2.667)
			(end -1.016 2.667)
			(stroke
				(width 0.1524)
				(type default)
			)
			(layer "F.SilkS")
		)
		(fp_line
			(start 1.016 2.667)
			(end 1.016 -2.667)
			(stroke
				(width 0.1524)
				(type default)
			)
			(layer "F.SilkS")
		)
		(fp_line
			(start -1.016 2.667)
			(end 1.016 2.667)
			(stroke
				(width 0.1524)
				(type default)
			)
			(layer "F.SilkS")
		)
		(fp_line
			(start 0.889 2.921)
			(end -0.889 2.921)
			(stroke
				(width 0.508)
				(type default)
			)
			(layer "F.SilkS")
		)
		(fp_rect
			(start -1.143 3.175)
			(end 1.143 -2.794)
			(stroke
				(width 0)
				(type default)
			)
			(fill no)
			(layer "F.CrtYd")
		)
		(fp_poly
			(pts
				(xy -1.143 -2.794) (xy 1.143 -2.794) (xy 1.143 3.175) (xy -1.143 3.175)
			)
			(stroke
				(width 0)
				(type default)
			)
			(fill no)
			(layer "F.Fab")
		)
		(pad "A" smd rect
			(at 0 -1.6891 90)
			(size 0.889 1.397)
			(layers "F.Cu" "F.Mask" "F.Paste")
			(net "FAN_TACH11")
		)
		(pad "K" smd rect
			(at 0 1.6891 90)
			(size 0.889 1.397)
			(layers "F.Cu" "F.Mask" "F.Paste")
			(net "P12V")
		)
	)
	(footprint ""
		(layer "F.Cu")
		(at 26.6954 -289.433)
		(property "Reference" "R178"
			(at 0 0 0)
			(layer "F.SilkS")
			(hide yes)
			(effects
				(font
					(size 1.27 1.27)
				)
			)
		)
		(property "Value" "0R1206-PAD-1-GP"
			(at 0 -5.0292 0)
			(unlocked yes)
			(layer "F.Fab")
			(hide yes)
			(effects
				(font
					(size 1.016 1.016)
					(thickness 0.1524)
				)
			)
		)
		(property "Device Type" "0R1206-PAD-1"
			(at 0 -6.5532 0)
			(unlocked yes)
			(layer "F.Fab")
			(hide yes)
			(effects
				(font
					(size 1.016 1.016)
					(thickness 0.1524)
				)
			)
		)
		(duplicate_pad_numbers_are_jumpers no)
		(fp_line
			(start -1.016 -2.2352)
			(end -1.016 2.2352)
			(stroke
				(width 0.1524)
				(type default)
			)
			(layer "F.SilkS")
		)
		(fp_line
			(start -1.016 2.2352)
			(end 1.016 2.2352)
			(stroke
				(width 0.1524)
				(type default)
			)
			(layer "F.SilkS")
		)
		(fp_line
			(start 1.016 -2.2352)
			(end -1.016 -2.2352)
			(stroke
				(width 0.1524)
				(type default)
			)
			(layer "F.SilkS")
		)
		(fp_line
			(start 1.016 2.2352)
			(end 1.016 -2.2352)
			(stroke
				(width 0.1524)
				(type default)
			)
			(layer "F.SilkS")
		)
		(fp_rect
			(start -1.0922 2.3114)
			(end 1.0922 -2.3114)
			(stroke
				(width 0)
				(type default)
			)
			(fill no)
			(layer "F.CrtYd")
		)
		(fp_poly
			(pts
				(xy -1.0922 -2.3114) (xy 1.0922 -2.3114) (xy 1.0922 2.3114) (xy -1.0922 2.3114)
			)
			(stroke
				(width 0)
				(type default)
			)
			(fill no)
			(layer "F.Fab")
		)
		(pad "1" smd rect
			(at 0 -1.397)
			(size 1.651 2.0574)
			(drill
				(offset 0 0.3937)
			)
			(layers "F.Cu" "F.Mask" "F.Paste")
			(net "P12V_FAN2")
		)
		(pad "2" smd rect
			(at 0 1.397)
			(size 1.651 2.0574)
			(drill
				(offset 0 -0.3937)
			)
			(layers "F.Cu" "F.Mask" "F.Paste")
			(net "P12V")
		)
	)
	(footprint ""
		(layer "F.Cu")
		(at 12.6746 -225.8822 180)
		(property "Reference" "R124"
			(at 0 0 180)
			(layer "F.SilkS")
			(hide yes)
			(effects
				(font
					(size 1.27 1.27)
				)
			)
		)
		(property "Value" "1K8R6J-GP"
			(at -0.0508 -4.8514 180)
			(unlocked yes)
			(layer "F.Fab")
			(hide yes)
			(effects
				(font
					(size 1.016 1.016)
					(thickness 0.1524)
				)
			)
		)
		(property "Device Type" "R1206H28"
			(at 0 -6.3754 180)
			(unlocked yes)
			(layer "F.Fab")
			(hide yes)
			(effects
				(font
					(size 1.016 1.016)
					(thickness 0.1524)
				)
			)
		)
		(duplicate_pad_numbers_are_jumpers no)
		(fp_line
			(start 1.016 2.2352)
			(end -1.016 2.2352)
			(stroke
				(width 0.1524)
				(type default)
			)
			(layer "F.SilkS")
		)
		(fp_line
			(start 1.016 -2.2352)
			(end 1.016 2.2352)
			(stroke
				(width 0.1524)
				(type default)
			)
			(layer "F.SilkS")
		)
		(fp_line
			(start -1.016 2.2352)
			(end -1.016 -2.2352)
			(stroke
				(width 0.1524)
				(type default)
			)
			(layer "F.SilkS")
		)
		(fp_line
			(start -1.016 -2.2352)
			(end 1.016 -2.2352)
			(stroke
				(width 0.1524)
				(type default)
			)
			(layer "F.SilkS")
		)
		(fp_rect
			(start -1.0922 2.3114)
			(end 1.0922 -2.3114)
			(stroke
				(width 0)
				(type default)
			)
			(fill no)
			(layer "F.CrtYd")
		)
		(fp_poly
			(pts
				(xy -1.0922 -2.3114) (xy 1.0922 -2.3114) (xy 1.0922 2.3114) (xy -1.0922 2.3114)
			)
			(stroke
				(width 0)
				(type default)
			)
			(fill no)
			(layer "F.Fab")
		)
		(pad "1" smd rect
			(at 0 -1.397 180)
			(size 1.651 1.27)
			(layers "F.Cu" "F.Mask" "F.Paste")
			(net "P12V")
		)
		(pad "2" smd rect
			(at 0 1.397 180)
			(size 1.651 1.27)
			(layers "F.Cu" "F.Mask" "F.Paste")
			(net "LED_DR_LED3_BLUE")
		)
	)
)
